# T6G (Grand Teton) — schematic netlist excerpt (pin names and nets, part order shuffled) for the footprints in the layout excerpt that follows; sources: Cadence DE-HDL packaged netlist, KiCad conversion of 04192023_DAF0TMB3IC0_F0TG_MB_C_brd_V02_OCP.brd

U51  ADC128D818CIMTXNOPB  ADC128D818CIMTX/NOPB IC  pkg TSSOP16XC  page 258
  VREF  = ADC128_2_VREF
  SDA  = SMB_SEN_TIC_2_3V3AUX_SDA
  SCL  = SMB_SEN_TIC_2_3V3AUX_SCL
  GND  = GND
  \v+\  = P3V3_ADC128_2_VCC
  \int#\  = TP_ADC128_2_INT
  A0  = ADC128_2_A0
  A1  = ADC128_2_A1
  IN7  = PVDD18_S5_P1_ADC_TIC
  IN6  = PVDD18_S5_P0_ADC_TIC
  IN5  = PVDD_33_S5_ADC_TIC
  IN4  = P1V8_CPU1_RT_1D_ADC_TIC
  IN3  = P1V8_CPU0_RT_1D_ADC_TIC
  IN2  = P1V2_AUX_ADC_TIC
  IN1  = P1V8_AUX_ADC_TIC
  IN0  = P5V_AUX_ADC_TIC

(kicad_pcb
	(version 20260206)
	(generator "pcbnew")
	(generator_version "10.0")
	(general
		(thickness 1.6)
		(legacy_teardrops no)
	)
	(paper "A4")
	(title_block
		(title "04192023_DAF0TMB3IC0_F0TG_MB_C_brd_V02_OCP.brd")
		(comment 1 "Grand Teton / footprints 7354-7354 of 8354")
	)
	(layers
		(0 "F.Cu" signal "TOP")
		(4 "In1.Cu" signal "GND")
		(6 "In2.Cu" signal "IN1")
		(8 "In3.Cu" signal "GND1")
		(10 "In4.Cu" signal "IN2")
		(12 "In5.Cu" signal "GND2")
		(14 "In6.Cu" signal "IN3")
		(16 "In7.Cu" signal "GND3")
		(18 "In8.Cu" signal "VCC")
		(20 "In9.Cu" signal "VCC1")
		(22 "In10.Cu" signal "GND4")
		(24 "In11.Cu" signal "IN4")
		(26 "In12.Cu" signal "GND5")
		(28 "In13.Cu" signal "IN5")
		(30 "In14.Cu" signal "GND6")
		(32 "In15.Cu" signal "IN6")
		(34 "In16.Cu" signal "GND7")
		(2 "B.Cu" signal "BOTTOM")
		(9 "F.Adhes" user "F.Adhesive")
		(11 "B.Adhes" user "B.Adhesive")
		(13 "F.Paste" user "Package Geometry/Pastemask Top")
		(15 "B.Paste" user "Package Geometry/Pastemask Bottom")
		(5 "F.SilkS" user "Ref Des/Silkscreen Top")
		(7 "B.SilkS" user "Ref Des/Silkscreen Bottom")
		(1 "F.Mask" user "Board Geometry/Soldermask Top")
		(3 "B.Mask" user "Board Geometry/Soldermask Bottom")
		(17 "Dwgs.User" user "User.Drawings")
		(19 "Cmts.User" user "User.Comments")
		(21 "Eco1.User" user "User.Eco1")
		(23 "Eco2.User" user "User.Eco2")
		(25 "Edge.Cuts" user "Board Geometry/Outline")
		(27 "Margin" user)
		(31 "F.CrtYd" user "Package Geometry/Place Bound Top")
		(29 "B.CrtYd" user "Package Geometry/Place Bound Bottom")
		(35 "F.Fab" user "Ref Des/Assembly Top")
		(33 "B.Fab" user "Ref Des/Assembly Bottom")
	)
	(footprint ""
		(layer "B.Cu")
		(at 222.408242 -326.534272 180)
		(property "Reference" "U51"
			(at 0.015494 -3.693922 0)
			(unlocked yes)
			(layer "B.SilkS")
			(effects
				(font
					(size 0.7874 0.5842)
					(thickness 0.1524)
				)
				(justify left mirror)
			)
		)
		(property "Value" ""
			(at 0 0 0)
			(layer "B.Fab")
			(effects
				(font
					(size 1.27 1.27)
				)
				(justify mirror)
			)
		)
		(duplicate_pad_numbers_are_jumpers no)
		(fp_line
			(start 1.868932 2.549906)
			(end -1.868932 2.549906)
			(stroke
				(width 0.1524)
				(type default)
			)
			(layer "B.SilkS")
		)
		(fp_line
			(start 1.868932 -2.549906)
			(end 1.868932 2.549906)
			(stroke
				(width 0.1524)
				(type default)
			)
			(layer "B.SilkS")
		)
		(fp_line
			(start 1.025906 -2.549906)
			(end 1.868932 -2.549906)
			(stroke
				(width 0.1524)
				(type default)
			)
			(layer "B.SilkS")
		)
		(fp_line
			(start 0 -1.524)
			(end 1.025906 -2.549906)
			(stroke
				(width 0.1524)
				(type default)
			)
			(layer "B.SilkS")
		)
		(fp_line
			(start -1.025906 -2.549906)
			(end 0 -1.524)
			(stroke
				(width 0.1524)
				(type default)
			)
			(layer "B.SilkS")
		)
		(fp_line
			(start -1.868932 2.549906)
			(end -1.868932 -2.549906)
			(stroke
				(width 0.1524)
				(type default)
			)
			(layer "B.SilkS")
		)
		(fp_line
			(start -1.868932 -2.549906)
			(end -1.025906 -2.549906)
			(stroke
				(width 0.1524)
				(type default)
			)
			(layer "B.SilkS")
		)
		(fp_poly
			(pts
				(xy 4.948682 -3.169666) (xy 4.290822 -3.943858) (xy 3.84556 -2.898902)
			)
			(stroke
				(width 0)
				(type default)
			)
			(fill yes)
			(layer "B.SilkS")
		)
		(fp_line
			(start 2.249932 2.549906)
			(end -2.249932 2.549906)
			(stroke
				(width 0.1)
				(type default)
			)
			(layer "B.Fab")
		)
		(fp_line
			(start 2.249932 -2.549906)
			(end 2.249932 2.549906)
			(stroke
				(width 0.1)
				(type default)
			)
			(layer "B.Fab")
		)
		(fp_line
			(start -2.249932 2.549906)
			(end -2.249932 -2.549906)
			(stroke
				(width 0.1)
				(type default)
			)
			(layer "B.Fab")
		)
		(fp_line
			(start -2.249932 -2.549906)
			(end 2.249932 -2.549906)
			(stroke
				(width 0.1)
				(type default)
			)
			(layer "B.Fab")
		)
		(fp_poly
			(pts
				(xy 4.7752 -1.787398) (xy 4.7752 -2.803398) (xy 3.7592 -2.295398)
			)
			(stroke
				(width 0)
				(type default)
			)
			(fill yes)
			(layer "B.Fab")
		)
		(pad "1" smd rect
			(at 2.800096 -2.275078 90)
			(size 0.3556 1.6002)
			(layers "B.Cu" "B.Mask" "B.Paste")
			(net "ADC128_2_VREF")
		)
		(pad "2" smd rect
			(at 2.800096 -1.625092 90)
			(size 0.3556 1.6002)
			(layers "B.Cu" "B.Mask" "B.Paste")
			(net "SMB_SEN_TIC_2_3V3AUX_SDA")
		)
		(pad "3" smd rect
			(at 2.800096 -0.975106 90)
			(size 0.3556 1.6002)
			(layers "B.Cu" "B.Mask" "B.Paste")
			(net "SMB_SEN_TIC_2_3V3AUX_SCL")
		)
		(pad "4" smd rect
			(at 2.800096 -0.32512 90)
			(size 0.3556 1.6002)
			(layers "B.Cu" "B.Mask" "B.Paste")
			(net "GND")
		)
		(pad "5" smd rect
			(at 2.800096 0.32512 90)
			(size 0.3556 1.6002)
			(layers "B.Cu" "B.Mask" "B.Paste")
			(net "P3V3_ADC128_2_VCC")
		)
		(pad "6" smd rect
			(at 2.800096 0.975106 90)
			(size 0.3556 1.6002)
			(layers "B.Cu" "B.Mask" "B.Paste")
			(net "TP_ADC128_2_INT")
		)
		(pad "7" smd rect
			(at 2.800096 1.625092 90)
			(size 0.3556 1.6002)
			(layers "B.Cu" "B.Mask" "B.Paste")
			(net "ADC128_2_A0")
		)
		(pad "8" smd rect
			(at 2.800096 2.275078 90)
			(size 0.3556 1.6002)
			(layers "B.Cu" "B.Mask" "B.Paste")
			(net "ADC128_2_A1")
		)
		(pad "9" smd rect
			(at -2.800096 2.275078 90)
			(size 0.3556 1.6002)
			(layers "B.Cu" "B.Mask" "B.Paste")
			(net "PVDD18_S5_P1_ADC_TIC")
		)
		(pad "10" smd rect
			(at -2.800096 1.625092 90)
			(size 0.3556 1.6002)
			(layers "B.Cu" "B.Mask" "B.Paste")
			(net "PVDD18_S5_P0_ADC_TIC")
		)
		(pad "11" smd rect
			(at -2.800096 0.975106 90)
			(size 0.3556 1.6002)
			(layers "B.Cu" "B.Mask" "B.Paste")
			(net "PVDD_33_S5_ADC_TIC")
		)
		(pad "12" smd rect
			(at -2.800096 0.32512 90)
			(size 0.3556 1.6002)
			(layers "B.Cu" "B.Mask" "B.Paste")
			(net "P1V8_CPU1_RT_1D_ADC_TIC")
		)
		(pad "13" smd rect
			(at -2.800096 -0.32512 90)
			(size 0.3556 1.6002)
			(layers "B.Cu" "B.Mask" "B.Paste")
			(net "P1V8_CPU0_RT_1D_ADC_TIC")
		)
		(pad "14" smd rect
			(at -2.800096 -0.975106 90)
			(size 0.3556 1.6002)
			(layers "B.Cu" "B.Mask" "B.Paste")
			(net "P1V2_AUX_ADC_TIC")
		)
		(pad "15" smd rect
			(at -2.800096 -1.625092 90)
			(size 0.3556 1.6002)
			(layers "B.Cu" "B.Mask" "B.Paste")
			(net "P1V8_AUX_ADC_TIC")
		)
		(pad "16" smd rect
			(at -2.800096 -2.275078 90)
			(size 0.3556 1.6002)
			(layers "B.Cu" "B.Mask" "B.Paste")
			(net "P5V_AUX_ADC_TIC")
		)
	)
)
